(kicad_pcb
	(version 20260206)
	(generator "pcbnew")
	(generator_version "10.0")
	(general
		(thickness 1.6)
		(legacy_teardrops no)
	)
	(paper "A4")
	(title_block
		(title "01162023_DA0F0TEBIF0_F0T_Expander_BD_F_brd_V02_OCP.brd")
		(comment 1 "Grand Teton / footprints 3595-3601 of 9728")
	)
	(layers
		(0 "F.Cu" signal "TOP")
		(4 "In1.Cu" signal "GND")
		(6 "In2.Cu" signal "VCC")
		(8 "In3.Cu" signal "VCC1")
		(10 "In4.Cu" signal "GND1")
		(12 "In5.Cu" signal "IN1")
		(14 "In6.Cu" signal "GND2")
		(16 "In7.Cu" signal "IN2")
		(18 "In8.Cu" signal "GND3")
		(20 "In9.Cu" signal "IN3")
		(22 "In10.Cu" signal "GND4")
		(24 "In11.Cu" signal "IN4")
		(26 "In12.Cu" signal "GND5")
		(28 "In13.Cu" signal "IN5")
		(30 "In14.Cu" signal "GND6")
		(32 "In15.Cu" signal "IN6")
		(34 "In16.Cu" signal "GND7")
		(2 "B.Cu" signal "BOTTOM")
		(9 "F.Adhes" user "F.Adhesive")
		(11 "B.Adhes" user "B.Adhesive")
		(13 "F.Paste" user "Package Geometry/Pastemask Top")
		(15 "B.Paste" user "Package Geometry/Pastemask Bottom")
		(5 "F.SilkS" user "Ref Des/Silkscreen Top")
		(7 "B.SilkS" user "Ref Des/Silkscreen Bottom")
		(1 "F.Mask" user "Board Geometry/Soldermask Top")
		(3 "B.Mask" user "Board Geometry/Soldermask Bottom")
		(17 "Dwgs.User" user "User.Drawings")
		(19 "Cmts.User" user "User.Comments")
		(21 "Eco1.User" user "User.Eco1")
		(23 "Eco2.User" user "User.Eco2")
		(25 "Edge.Cuts" user "Board Geometry/Outline")
		(27 "Margin" user)
		(31 "F.CrtYd" user "Package Geometry/Place Bound Top")
		(29 "B.CrtYd" user "Package Geometry/Place Bound Bottom")
		(35 "F.Fab" user "Ref Des/Assembly Top")
		(33 "B.Fab" user "Ref Des/Assembly Bottom")
	)
	(footprint ""
		(layer "F.Cu")
		(at 7.398258 -304.850546 90)
		(property "Reference" "PC220"
			(at 0 0 90)
			(layer "F.SilkS")
			(hide yes)
			(effects
				(font
					(size 1.27 1.27)
				)
			)
		)
		(property "Value" ""
			(at 0 0 90)
			(layer "F.Fab")
			(effects
				(font
					(size 1.27 1.27)
				)
			)
		)
		(duplicate_pad_numbers_are_jumpers no)
		(fp_line
			(start 0.7874 -0.4064)
			(end 0.7874 0.4064)
			(stroke
				(width 0.1524)
				(type default)
			)
			(layer "F.SilkS")
		)
		(fp_line
			(start -0.7874 -0.4064)
			(end 0.7874 -0.4064)
			(stroke
				(width 0.1524)
				(type default)
			)
			(layer "F.SilkS")
		)
		(fp_line
			(start 0.7874 0.4064)
			(end -0.7874 0.4064)
			(stroke
				(width 0.1524)
				(type default)
			)
			(layer "F.SilkS")
		)
		(fp_line
			(start -0.7874 0.4064)
			(end -0.7874 -0.4064)
			(stroke
				(width 0.1524)
				(type default)
			)
			(layer "F.SilkS")
		)
		(fp_line
			(start -0.12065 -0.305054)
			(end -0.12065 -0.2794)
			(stroke
				(width 0.1)
				(type default)
			)
			(layer "F.Fab")
		)
		(fp_line
			(start -0.67945 -0.305054)
			(end -0.12065 -0.305054)
			(stroke
				(width 0.1)
				(type default)
			)
			(layer "F.Fab")
		)
		(fp_line
			(start 0.67945 -0.3048)
			(end 0.67945 0.3048)
			(stroke
				(width 0.1)
				(type default)
			)
			(layer "F.Fab")
		)
		(fp_line
			(start 0.12065 -0.3048)
			(end 0.67945 -0.3048)
			(stroke
				(width 0.1)
				(type default)
			)
			(layer "F.Fab")
		)
		(fp_line
			(start 0.12065 -0.2794)
			(end 0.12065 -0.3048)
			(stroke
				(width 0.1)
				(type default)
			)
			(layer "F.Fab")
		)
		(fp_line
			(start -0.12065 -0.2794)
			(end 0.12065 -0.2794)
			(stroke
				(width 0.1)
				(type default)
			)
			(layer "F.Fab")
		)
		(fp_line
			(start 0.120396 0.2794)
			(end -0.12065 0.2794)
			(stroke
				(width 0.1)
				(type default)
			)
			(layer "F.Fab")
		)
		(fp_line
			(start -0.12065 0.2794)
			(end -0.12065 0.3048)
			(stroke
				(width 0.1)
				(type default)
			)
			(layer "F.Fab")
		)
		(fp_line
			(start 0.67945 0.3048)
			(end 0.120396 0.3048)
			(stroke
				(width 0.1)
				(type default)
			)
			(layer "F.Fab")
		)
		(fp_line
			(start 0.120396 0.3048)
			(end 0.120396 0.2794)
			(stroke
				(width 0.1)
				(type default)
			)
			(layer "F.Fab")
		)
		(fp_line
			(start -0.12065 0.3048)
			(end -0.67945 0.3048)
			(stroke
				(width 0.1)
				(type default)
			)
			(layer "F.Fab")
		)
		(fp_line
			(start -0.67945 0.3048)
			(end -0.67945 -0.305054)
			(stroke
				(width 0.1)
				(type default)
			)
			(layer "F.Fab")
		)
		(pad "1" smd circle
			(at -0.40005 0 90)
			(size 0 0)
			(layers "F.Cu" "F.Mask" "F.Paste")
			(net "P1V25_PEX0_VCC")
		)
		(pad "2" smd circle
			(at 0.40005 0 90)
			(size 0 0)
			(layers "F.Cu" "F.Mask" "F.Paste")
			(net "GND")
		)
	)
	(footprint ""
		(layer "F.Cu")
		(at 331.457046 -236.871256 -90)
		(property "Reference" "R1786"
			(at 0 0 270)
			(layer "F.SilkS")
			(hide yes)
			(effects
				(font
					(size 1.27 1.27)
				)
			)
		)
		(property "Value" ""
			(at 0 0 270)
			(layer "F.Fab")
			(effects
				(font
					(size 1.27 1.27)
				)
			)
		)
		(duplicate_pad_numbers_are_jumpers no)
		(fp_line
			(start -0.7874 0.4064)
			(end -0.7874 -0.4064)
			(stroke
				(width 0.1524)
				(type default)
			)
			(layer "F.SilkS")
		)
		(fp_line
			(start 0.7874 0.4064)
			(end -0.7874 0.4064)
			(stroke
				(width 0.1524)
				(type default)
			)
			(layer "F.SilkS")
		)
		(fp_line
			(start -0.7874 -0.4064)
			(end 0.7874 -0.4064)
			(stroke
				(width 0.1524)
				(type default)
			)
			(layer "F.SilkS")
		)
		(fp_line
			(start 0.7874 -0.4064)
			(end 0.7874 0.4064)
			(stroke
				(width 0.1524)
				(type default)
			)
			(layer "F.SilkS")
		)
		(fp_line
			(start -0.67945 0.3048)
			(end -0.67945 -0.305054)
			(stroke
				(width 0.1)
				(type default)
			)
			(layer "F.Fab")
		)
		(fp_line
			(start -0.12065 0.3048)
			(end -0.67945 0.3048)
			(stroke
				(width 0.1)
				(type default)
			)
			(layer "F.Fab")
		)
		(fp_line
			(start 0.120396 0.3048)
			(end 0.120396 0.2794)
			(stroke
				(width 0.1)
				(type default)
			)
			(layer "F.Fab")
		)
		(fp_line
			(start 0.67945 0.3048)
			(end 0.120396 0.3048)
			(stroke
				(width 0.1)
				(type default)
			)
			(layer "F.Fab")
		)
		(fp_line
			(start -0.12065 0.2794)
			(end -0.12065 0.3048)
			(stroke
				(width 0.1)
				(type default)
			)
			(layer "F.Fab")
		)
		(fp_line
			(start 0.120396 0.2794)
			(end -0.12065 0.2794)
			(stroke
				(width 0.1)
				(type default)
			)
			(layer "F.Fab")
		)
		(fp_line
			(start -0.12065 -0.2794)
			(end 0.12065 -0.2794)
			(stroke
				(width 0.1)
				(type default)
			)
			(layer "F.Fab")
		)
		(fp_line
			(start 0.12065 -0.2794)
			(end 0.12065 -0.3048)
			(stroke
				(width 0.1)
				(type default)
			)
			(layer "F.Fab")
		)
		(fp_line
			(start 0.12065 -0.3048)
			(end 0.67945 -0.3048)
			(stroke
				(width 0.1)
				(type default)
			)
			(layer "F.Fab")
		)
		(fp_line
			(start 0.67945 -0.3048)
			(end 0.67945 0.3048)
			(stroke
				(width 0.1)
				(type default)
			)
			(layer "F.Fab")
		)
		(fp_line
			(start -0.67945 -0.305054)
			(end -0.12065 -0.305054)
			(stroke
				(width 0.1)
				(type default)
			)
			(layer "F.Fab")
		)
		(fp_line
			(start -0.12065 -0.305054)
			(end -0.12065 -0.2794)
			(stroke
				(width 0.1)
				(type default)
			)
			(layer "F.Fab")
		)
		(pad "1" smd circle
			(at -0.40005 0 270)
			(size 0 0)
			(layers "F.Cu" "F.Mask" "F.Paste")
			(net "P3V3_AUX")
		)
		(pad "2" smd circle
			(at 0.40005 0 270)
			(size 0 0)
			(layers "F.Cu" "F.Mask" "F.Paste")
			(net "RST_MB_PERST_0_ISO_R_N")
		)
	)
	(footprint ""
		(layer "F.Cu")
		(at 281.856434 -20.467574 180)
		(property "Reference" "R1692"
			(at 0 0 180)
			(layer "F.SilkS")
			(hide yes)
			(effects
				(font
					(size 1.27 1.27)
				)
			)
		)
		(property "Value" ""
			(at 0 0 180)
			(layer "F.Fab")
			(effects
				(font
					(size 1.27 1.27)
				)
			)
		)
		(duplicate_pad_numbers_are_jumpers no)
		(fp_line
			(start 0.7874 0.4064)
			(end -0.7874 0.4064)
			(stroke
				(width 0.1524)
				(type default)
			)
			(layer "F.SilkS")
		)
		(fp_line
			(start 0.7874 -0.4064)
			(end 0.7874 0.4064)
			(stroke
				(width 0.1524)
				(type default)
			)
			(layer "F.SilkS")
		)
		(fp_line
			(start -0.7874 0.4064)
			(end -0.7874 -0.4064)
			(stroke
				(width 0.1524)
				(type default)
			)
			(layer "F.SilkS")
		)
		(fp_line
			(start -0.7874 -0.4064)
			(end 0.7874 -0.4064)
			(stroke
				(width 0.1524)
				(type default)
			)
			(layer "F.SilkS")
		)
		(fp_line
			(start 0.67945 0.3048)
			(end 0.120396 0.3048)
			(stroke
				(width 0.1)
				(type default)
			)
			(layer "F.Fab")
		)
		(fp_line
			(start 0.67945 -0.3048)
			(end 0.67945 0.3048)
			(stroke
				(width 0.1)
				(type default)
			)
			(layer "F.Fab")
		)
		(fp_line
			(start 0.12065 -0.2794)
			(end 0.12065 -0.3048)
			(stroke
				(width 0.1)
				(type default)
			)
			(layer "F.Fab")
		)
		(fp_line
			(start 0.12065 -0.3048)
			(end 0.67945 -0.3048)
			(stroke
				(width 0.1)
				(type default)
			)
			(layer "F.Fab")
		)
		(fp_line
			(start 0.120396 0.3048)
			(end 0.120396 0.2794)
			(stroke
				(width 0.1)
				(type default)
			)
			(layer "F.Fab")
		)
		(fp_line
			(start 0.120396 0.2794)
			(end -0.12065 0.2794)
			(stroke
				(width 0.1)
				(type default)
			)
			(layer "F.Fab")
		)
		(fp_line
			(start -0.12065 0.3048)
			(end -0.67945 0.3048)
			(stroke
				(width 0.1)
				(type default)
			)
			(layer "F.Fab")
		)
		(fp_line
			(start -0.12065 0.2794)
			(end -0.12065 0.3048)
			(stroke
				(width 0.1)
				(type default)
			)
			(layer "F.Fab")
		)
		(fp_line
			(start -0.12065 -0.2794)
			(end 0.12065 -0.2794)
			(stroke
				(width 0.1)
				(type default)
			)
			(layer "F.Fab")
		)
		(fp_line
			(start -0.12065 -0.305054)
			(end -0.12065 -0.2794)
			(stroke
				(width 0.1)
				(type default)
			)
			(layer "F.Fab")
		)
		(fp_line
			(start -0.67945 0.3048)
			(end -0.67945 -0.305054)
			(stroke
				(width 0.1)
				(type default)
			)
			(layer "F.Fab")
		)
		(fp_line
			(start -0.67945 -0.305054)
			(end -0.12065 -0.305054)
			(stroke
				(width 0.1)
				(type default)
			)
			(layer "F.Fab")
		)
		(pad "1" smd circle
			(at -0.40005 0 180)
			(size 0 0)
			(layers "F.Cu" "F.Mask" "F.Paste")
			(net "P3V3_SSD9")
		)
		(pad "2" smd circle
			(at 0.40005 0 180)
			(size 0 0)
			(layers "F.Cu" "F.Mask" "F.Paste")
			(net "SMB_ISO_SSD9_SDA")
		)
	)
	(footprint ""
		(layer "F.Cu")
		(at 18.431256 -123.903994 -90)
		(property "Reference" "PC453"
			(at 0 0 270)
			(layer "F.SilkS")
			(hide yes)
			(effects
				(font
					(size 1.27 1.27)
				)
			)
		)
		(property "Value" ""
			(at 0 0 270)
			(layer "F.Fab")
			(effects
				(font
					(size 1.27 1.27)
				)
			)
		)
		(duplicate_pad_numbers_are_jumpers no)
		(fp_line
			(start -1.524 0.762)
			(end -1.524 -0.762)
			(stroke
				(width 0.1524)
				(type default)
			)
			(layer "F.SilkS")
		)
		(fp_line
			(start 1.524 0.762)
			(end -1.524 0.762)
			(stroke
				(width 0.1524)
				(type default)
			)
			(layer "F.SilkS")
		)
		(fp_line
			(start -1.524 -0.762)
			(end 1.524 -0.762)
			(stroke
				(width 0.1524)
				(type default)
			)
			(layer "F.SilkS")
		)
		(fp_line
			(start 1.524 -0.762)
			(end 1.524 0.762)
			(stroke
				(width 0.1524)
				(type default)
			)
			(layer "F.SilkS")
		)
		(fp_line
			(start -1.1049 0.724916)
			(end 1.1049 0.724916)
			(stroke
				(width 0.1)
				(type default)
			)
			(layer "F.Fab")
		)
		(fp_line
			(start 1.1049 0.724916)
			(end 1.1049 -0.724916)
			(stroke
				(width 0.1)
				(type default)
			)
			(layer "F.Fab")
		)
		(fp_line
			(start -1.1049 -0.724916)
			(end -1.1049 0.724916)
			(stroke
				(width 0.1)
				(type default)
			)
			(layer "F.Fab")
		)
		(fp_line
			(start 1.1049 -0.724916)
			(end -1.1049 -0.724916)
			(stroke
				(width 0.1)
				(type default)
			)
			(layer "F.Fab")
		)
		(pad "1" smd rect
			(at -0.889 0 90)
			(size 1.016 1.27)
			(layers "F.Cu" "F.Mask" "F.Paste")
			(net "P3V3_NIC0")
		)
		(pad "2" smd rect
			(at 0.889 0 90)
			(size 1.016 1.27)
			(layers "F.Cu" "F.Mask" "F.Paste")
			(net "GND")
		)
	)
	(footprint ""
		(layer "F.Cu")
		(at 263.496044 -77.279754 90)
		(property "Reference" "R1075"
			(at 0 0 90)
			(layer "F.SilkS")
			(hide yes)
			(effects
				(font
					(size 1.27 1.27)
				)
			)
		)
		(property "Value" ""
			(at 0 0 90)
			(layer "F.Fab")
			(effects
				(font
					(size 1.27 1.27)
				)
			)
		)
		(duplicate_pad_numbers_are_jumpers no)
		(fp_line
			(start 0.7874 0.4064)
			(end -0.7874 0.4064)
			(stroke
				(width 0.1524)
				(type default)
			)
			(layer "F.SilkS")
		)
		(fp_line
			(start -0.12065 -0.305054)
			(end -0.12065 -0.2794)
			(stroke
				(width 0.1)
				(type default)
			)
			(layer "F.Fab")
		)
		(fp_line
			(start -0.67945 -0.305054)
			(end -0.12065 -0.305054)
			(stroke
				(width 0.1)
				(type default)
			)
			(layer "F.Fab")
		)
		(fp_line
			(start 0.67945 -0.3048)
			(end 0.67945 0.3048)
			(stroke
				(width 0.1)
				(type default)
			)
			(layer "F.Fab")
		)
		(fp_line
			(start 0.12065 -0.3048)
			(end 0.67945 -0.3048)
			(stroke
				(width 0.1)
				(type default)
			)
			(layer "F.Fab")
		)
		(fp_line
			(start 0.12065 -0.2794)
			(end 0.12065 -0.3048)
			(stroke
				(width 0.1)
				(type default)
			)
			(layer "F.Fab")
		)
		(fp_line
			(start -0.12065 -0.2794)
			(end 0.12065 -0.2794)
			(stroke
				(width 0.1)
				(type default)
			)
			(layer "F.Fab")
		)
		(fp_line
			(start 0.120396 0.2794)
			(end -0.12065 0.2794)
			(stroke
				(width 0.1)
				(type default)
			)
			(layer "F.Fab")
		)
		(fp_line
			(start -0.12065 0.2794)
			(end -0.12065 0.3048)
			(stroke
				(width 0.1)
				(type default)
			)
			(layer "F.Fab")
		)
		(fp_line
			(start 0.67945 0.3048)
			(end 0.120396 0.3048)
			(stroke
				(width 0.1)
				(type default)
			)
			(layer "F.Fab")
		)
		(fp_line
			(start 0.120396 0.3048)
			(end 0.120396 0.2794)
			(stroke
				(width 0.1)
				(type default)
			)
			(layer "F.Fab")
		)
		(fp_line
			(start -0.12065 0.3048)
			(end -0.67945 0.3048)
			(stroke
				(width 0.1)
				(type default)
			)
			(layer "F.Fab")
		)
		(fp_line
			(start -0.67945 0.3048)
			(end -0.67945 -0.305054)
			(stroke
				(width 0.1)
				(type default)
			)
			(layer "F.Fab")
		)
		(pad "1" smd circle
			(at -0.40005 0 90)
			(size 0 0)
			(layers "F.Cu" "F.Mask" "F.Paste")
			(net "CLK_100M_CK440Q_2_DB800ZL_R_DP")
		)
		(pad "2" smd circle
			(at 0.40005 0 90)
			(size 0 0)
			(layers "F.Cu" "F.Mask" "F.Paste")
			(net "CLK_100M_CK440Q_2_DB800ZL_DP")
		)
	)
	(footprint ""
		(layer "F.Cu")
		(at 4.297426 -40.6654)
		(property "Reference" "PU81"
			(at -2.242566 -2.831338 90)
			(unlocked yes)
			(layer "F.SilkS")
			(effects
				(font
					(size 0.7874 0.5842)
					(thickness 0.1524)
				)
			)
		)
		(property "Value" ""
			(at 0 0 0)
			(layer "F.Fab")
			(effects
				(font
					(size 1.27 1.27)
				)
			)
		)
		(duplicate_pad_numbers_are_jumpers no)
		(fp_line
			(start -1.239774 -1.495298)
			(end 1.239774 -1.495298)
			(stroke
				(width 0.1524)
				(type default)
			)
			(layer "F.SilkS")
		)
		(fp_line
			(start -1.239774 1.495298)
			(end -1.239774 -1.495298)
			(stroke
				(width 0.1524)
				(type default)
			)
			(layer "F.SilkS")
		)
		(fp_line
			(start 1.239774 -1.495298)
			(end 1.239774 1.495298)
			(stroke
				(width 0.1524)
				(type default)
			)
			(layer "F.SilkS")
		)
		(fp_line
			(start 1.239774 1.495298)
			(end -1.239774 1.495298)
			(stroke
				(width 0.1524)
				(type default)
			)
			(layer "F.SilkS")
		)
		(fp_poly
			(pts
				(xy -2.195576 -1.29921) (xy -2.914142 -0.580644) (xy -1.83642 -0.221488)
			)
			(stroke
				(width 0)
				(type default)
			)
			(fill yes)
			(layer "F.SilkS")
		)
		(fp_line
			(start -0.8001 -1.050036)
			(end 0.8001 -1.050036)
			(stroke
				(width 0.1)
				(type default)
			)
			(layer "F.Fab")
		)
		(fp_line
			(start -0.8001 1.050036)
			(end -0.8001 -1.050036)
			(stroke
				(width 0.1)
				(type default)
			)
			(layer "F.Fab")
		)
		(fp_line
			(start 0.8001 -1.050036)
			(end 0.8001 1.050036)
			(stroke
				(width 0.1)
				(type default)
			)
			(layer "F.Fab")
		)
		(fp_line
			(start 0.8001 1.050036)
			(end -0.8001 1.050036)
			(stroke
				(width 0.1)
				(type default)
			)
			(layer "F.Fab")
		)
		(fp_poly
			(pts
				(xy -2.458974 -0.508) (xy -2.458974 0.508) (xy -1.442974 0)
			)
			(stroke
				(width 0)
				(type default)
			)
			(fill yes)
			(layer "F.Fab")
		)
		(pad "1_2" smd circle
			(at -0.374904 0 90)
			(size 0 0)
			(layers "F.Cu" "F.Mask" "F.Paste")
			(net "P3V3_AUX")
		)
		(pad "3" smd rect
			(at -0.499872 0.999998)
			(size 0.254 0.7112)
			(layers "F.Cu" "F.Mask" "F.Paste")
			(net "GND")
		)
		(pad "4" smd rect
			(at 0 0.999998)
			(size 0.254 0.7112)
			(layers "F.Cu" "F.Mask" "F.Paste")
			(net "P3V3_SSD0_CO_ILIMIT")
		)
		(pad "5" smd rect
			(at 0.499872 0.999998)
			(size 0.254 0.7112)
			(layers "F.Cu" "F.Mask" "F.Paste")
			(net "P3V3_SSD0_CO_MODE")
		)
		(pad "6_7" smd circle
			(at 0.374904 0 270)
			(size 0 0)
			(layers "F.Cu" "F.Mask" "F.Paste")
			(net "P3V3_SSD0")
		)
		(pad "8" smd rect
			(at 0.499872 -0.999998)
			(size 0.254 0.7112)
			(layers "F.Cu" "F.Mask" "F.Paste")
			(net "P3V3_SSD0_CO_GATE")
		)
		(pad "9" smd rect
			(at 0 -0.999998)
			(size 0.254 0.7112)
			(layers "F.Cu" "F.Mask" "F.Paste")
			(net "P3V3_SSD0_CO_EN")
		)
		(pad "10" smd rect
			(at -0.499872 -0.999998)
			(size 0.254 0.7112)
			(layers "F.Cu" "F.Mask" "F.Paste")
			(net "P3V3_SSD0_CO_DV_DT")
		)
	)
	(footprint ""
		(layer "F.Cu")
		(at 91.992704 -118.446804)
		(property "Reference" "PC663"
			(at 0 0 0)
			(layer "F.SilkS")
			(hide yes)
			(effects
				(font
					(size 1.27 1.27)
				)
			)
		)
		(property "Value" ""
			(at 0 0 0)
			(layer "F.Fab")
			(effects
				(font
					(size 1.27 1.27)
				)
			)
		)
		(duplicate_pad_numbers_are_jumpers no)
		(fp_line
			(start -1.524 -0.762)
			(end 1.524 -0.762)
			(stroke
				(width 0.1524)
				(type default)
			)
			(layer "F.SilkS")
		)
		(fp_line
			(start -1.524 0.762)
			(end -1.524 -0.762)
			(stroke
				(width 0.1524)
				(type default)
			)
			(layer "F.SilkS")
		)
		(fp_line
			(start 1.524 -0.762)
			(end 1.524 0.762)
			(stroke
				(width 0.1524)
				(type default)
			)
			(layer "F.SilkS")
		)
		(fp_line
			(start 1.524 0.762)
			(end -1.524 0.762)
			(stroke
				(width 0.1524)
				(type default)
			)
			(layer "F.SilkS")
		)
		(fp_line
			(start -1.1049 -0.724916)
			(end -1.1049 0.724916)
			(stroke
				(width 0.1)
				(type default)
			)
			(layer "F.Fab")
		)
		(fp_line
			(start -1.1049 0.724916)
			(end 1.1049 0.724916)
			(stroke
				(width 0.1)
				(type default)
			)
			(layer "F.Fab")
		)
		(fp_line
			(start 1.1049 -0.724916)
			(end -1.1049 -0.724916)
			(stroke
				(width 0.1)
				(type default)
			)
			(layer "F.Fab")
		)
		(fp_line
			(start 1.1049 0.724916)
			(end 1.1049 -0.724916)
			(stroke
				(width 0.1)
				(type default)
			)
			(layer "F.Fab")
		)
		(pad "1" smd rect
			(at -0.889 0 180)
			(size 1.016 1.27)
			(layers "F.Cu" "F.Mask" "F.Paste")
			(net "P3V3_NIC1")
		)
		(pad "2" smd rect
			(at 0.889 0 180)
			(size 1.016 1.27)
			(layers "F.Cu" "F.Mask" "F.Paste")
			(net "GND")
		)
	)
)
